# T6G (Grand Teton) — schematic netlist excerpt (pin names and nets, part order shuffled) for the footprints in the layout excerpt that follows; sources: Cadence DE-HDL packaged netlist, KiCad conversion of 04192023_DAF0TMB3IC0_F0TG_MB_C_brd_V02_OCP.brd

PC6804  Q_CAPP  390UF 2.5V 20% ALUM  pkg SMLF  page 361 : A = P1V8_CPU1_RT_1D ; B = GND
C6646  Q_CAP_DIFFBUS  DIFF BUS_0.22UF 6.3V 20% X6S  pkg C0201  page 319 : \1\ = P5E_CPU1_P0_TX_BUF_C_DN<8> ; \2\ = P5E_CPU1_P0_TX_BUF_DN<8>
PC440_1  Q_CAP  1UF 25V 10% X6S  pkg C0402  page 222 : A = SW_P12V_AUX_PVDDIO_P1_FLT ; B = GND

(kicad_pcb
	(version 20260206)
	(generator "pcbnew")
	(generator_version "10.0")
	(general
		(thickness 1.6)
		(legacy_teardrops no)
	)
	(paper "A4")
	(title_block
		(title "04192023_DAF0TMB3IC0_F0TG_MB_C_brd_V02_OCP.brd")
		(comment 1 "Grand Teton / footprints 924-926 of 8354")
	)
	(layers
		(0 "F.Cu" signal "TOP")
		(4 "In1.Cu" signal "GND")
		(6 "In2.Cu" signal "IN1")
		(8 "In3.Cu" signal "GND1")
		(10 "In4.Cu" signal "IN2")
		(12 "In5.Cu" signal "GND2")
		(14 "In6.Cu" signal "IN3")
		(16 "In7.Cu" signal "GND3")
		(18 "In8.Cu" signal "VCC")
		(20 "In9.Cu" signal "VCC1")
		(22 "In10.Cu" signal "GND4")
		(24 "In11.Cu" signal "IN4")
		(26 "In12.Cu" signal "GND5")
		(28 "In13.Cu" signal "IN5")
		(30 "In14.Cu" signal "GND6")
		(32 "In15.Cu" signal "IN6")
		(34 "In16.Cu" signal "GND7")
		(2 "B.Cu" signal "BOTTOM")
		(9 "F.Adhes" user "F.Adhesive")
		(11 "B.Adhes" user "B.Adhesive")
		(13 "F.Paste" user "Package Geometry/Pastemask Top")
		(15 "B.Paste" user "Package Geometry/Pastemask Bottom")
		(5 "F.SilkS" user "Ref Des/Silkscreen Top")
		(7 "B.SilkS" user "Ref Des/Silkscreen Bottom")
		(1 "F.Mask" user "Board Geometry/Soldermask Top")
		(3 "B.Mask" user "Board Geometry/Soldermask Bottom")
		(17 "Dwgs.User" user "User.Drawings")
		(19 "Cmts.User" user "User.Comments")
		(21 "Eco1.User" user "User.Eco1")
		(23 "Eco2.User" user "User.Eco2")
		(25 "Edge.Cuts" user "Board Geometry/Outline")
		(27 "Margin" user)
		(31 "F.CrtYd" user "Package Geometry/Place Bound Top")
		(29 "B.CrtYd" user "Package Geometry/Place Bound Bottom")
		(35 "F.Fab" user "Ref Des/Assembly Top")
		(33 "B.Fab" user "Ref Des/Assembly Bottom")
	)
	(footprint ""
		(layer "F.Cu")
		(at 226.421442 -315.82868 90)
		(property "Reference" "PC6804"
			(at -1.75768 -4.906772 90)
			(unlocked yes)
			(layer "F.SilkS")
			(effects
				(font
					(size 0.7874 0.5842)
					(thickness 0.1524)
				)
				(justify left)
			)
		)
		(property "Value" ""
			(at 0 0 90)
			(layer "F.Fab")
			(effects
				(font
					(size 1.27 1.27)
				)
			)
		)
		(duplicate_pad_numbers_are_jumpers no)
		(fp_line
			(start 2.750058 -2.750058)
			(end -1.988058 -2.750058)
			(stroke
				(width 0.1524)
				(type default)
			)
			(layer "F.SilkS")
		)
		(fp_line
			(start -1.988058 -2.750058)
			(end -2.750058 -1.988058)
			(stroke
				(width 0.1524)
				(type default)
			)
			(layer "F.SilkS")
		)
		(fp_line
			(start -2.750058 -1.988058)
			(end -2.750058 -0.9398)
			(stroke
				(width 0.1524)
				(type default)
			)
			(layer "F.SilkS")
		)
		(fp_line
			(start 2.750058 -0.9398)
			(end 2.750058 -2.750058)
			(stroke
				(width 0.1524)
				(type default)
			)
			(layer "F.SilkS")
		)
		(fp_line
			(start -2.750058 0.9398)
			(end -2.750058 1.988058)
			(stroke
				(width 0.1524)
				(type default)
			)
			(layer "F.SilkS")
		)
		(fp_line
			(start -2.750058 1.988058)
			(end -1.988058 2.750058)
			(stroke
				(width 0.1524)
				(type default)
			)
			(layer "F.SilkS")
		)
		(fp_line
			(start 2.750058 2.750058)
			(end 2.750058 0.9398)
			(stroke
				(width 0.1524)
				(type default)
			)
			(layer "F.SilkS")
		)
		(fp_line
			(start -1.988058 2.750058)
			(end 2.750058 2.750058)
			(stroke
				(width 0.1524)
				(type default)
			)
			(layer "F.SilkS")
		)
		(fp_line
			(start 2.750058 -2.750058)
			(end -2.750058 -2.750058)
			(stroke
				(width 0.1)
				(type default)
			)
			(layer "F.Fab")
		)
		(fp_line
			(start -2.750058 -2.750058)
			(end -2.750058 2.750058)
			(stroke
				(width 0.1)
				(type default)
			)
			(layer "F.Fab")
		)
		(fp_line
			(start 2.750058 2.750058)
			(end 2.750058 -2.750058)
			(stroke
				(width 0.1)
				(type default)
			)
			(layer "F.Fab")
		)
		(fp_line
			(start -2.750058 2.750058)
			(end 2.750058 2.750058)
			(stroke
				(width 0.1)
				(type default)
			)
			(layer "F.Fab")
		)
		(pad "1" smd rect
			(at -2.199894 0 180)
			(size 1.6002 3.0226)
			(layers "F.Cu" "F.Mask" "F.Paste")
			(net "P1V8_CPU1_RT_1D")
		)
		(pad "2" smd rect
			(at 2.199894 0 180)
			(size 1.6002 3.0226)
			(layers "F.Cu" "F.Mask" "F.Paste")
			(net "GND")
		)
	)
	(footprint ""
		(layer "F.Cu")
		(at 72.274684 -408.517344 -90)
		(property "Reference" "C6646"
			(at 0 0 270)
			(layer "F.SilkS")
			(hide yes)
			(effects
				(font
					(size 1.27 1.27)
				)
			)
		)
		(property "Value" ""
			(at 0 0 270)
			(layer "F.Fab")
			(effects
				(font
					(size 1.27 1.27)
				)
			)
		)
		(duplicate_pad_numbers_are_jumpers no)
		(fp_line
			(start -0.299974 0.150114)
			(end -0.299974 -0.150114)
			(stroke
				(width 0.1)
				(type default)
			)
			(layer "F.Fab")
		)
		(fp_line
			(start 0.299974 0.150114)
			(end -0.299974 0.150114)
			(stroke
				(width 0.1)
				(type default)
			)
			(layer "F.Fab")
		)
		(fp_line
			(start -0.299974 -0.150114)
			(end 0.299974 -0.150114)
			(stroke
				(width 0.1)
				(type default)
			)
			(layer "F.Fab")
		)
		(fp_line
			(start 0.299974 -0.150114)
			(end 0.299974 0.150114)
			(stroke
				(width 0.1)
				(type default)
			)
			(layer "F.Fab")
		)
		(pad "1" smd rect
			(at -0.2667 0 270)
			(size 0.3048 0.381)
			(layers "F.Cu" "F.Mask" "F.Paste")
			(net "P5E_CPU1_P0_TX_BUF_C_DN<8>")
		)
		(pad "2" smd rect
			(at 0.2667 0 270)
			(size 0.3048 0.381)
			(layers "F.Cu" "F.Mask" "F.Paste")
			(net "P5E_CPU1_P0_TX_BUF_DN<8>")
		)
	)
	(footprint ""
		(layer "F.Cu")
		(at 57.17794 -346.87129 -90)
		(property "Reference" "PC440_1"
			(at 0 0 270)
			(layer "F.SilkS")
			(hide yes)
			(effects
				(font
					(size 1.27 1.27)
				)
			)
		)
		(property "Value" ""
			(at 0 0 270)
			(layer "F.Fab")
			(effects
				(font
					(size 1.27 1.27)
				)
			)
		)
		(duplicate_pad_numbers_are_jumpers no)
		(fp_line
			(start -0.7874 0.4064)
			(end -0.7874 -0.4064)
			(stroke
				(width 0.1524)
				(type default)
			)
			(layer "F.SilkS")
		)
		(fp_line
			(start 0.7874 0.4064)
			(end -0.7874 0.4064)
			(stroke
				(width 0.1524)
				(type default)
			)
			(layer "F.SilkS")
		)
		(fp_line
			(start -0.7874 -0.4064)
			(end 0.7874 -0.4064)
			(stroke
				(width 0.1524)
				(type default)
			)
			(layer "F.SilkS")
		)
		(fp_line
			(start 0.7874 -0.4064)
			(end 0.7874 0.4064)
			(stroke
				(width 0.1524)
				(type default)
			)
			(layer "F.SilkS")
		)
		(fp_line
			(start -0.67945 0.3048)
			(end -0.67945 -0.305054)
			(stroke
				(width 0.1)
				(type default)
			)
			(layer "F.Fab")
		)
		(fp_line
			(start -0.12065 0.3048)
			(end -0.67945 0.3048)
			(stroke
				(width 0.1)
				(type default)
			)
			(layer "F.Fab")
		)
		(fp_line
			(start 0.120396 0.3048)
			(end 0.120396 0.2794)
			(stroke
				(width 0.1)
				(type default)
			)
			(layer "F.Fab")
		)
		(fp_line
			(start 0.67945 0.3048)
			(end 0.120396 0.3048)
			(stroke
				(width 0.1)
				(type default)
			)
			(layer "F.Fab")
		)
		(fp_line
			(start -0.12065 0.2794)
			(end -0.12065 0.3048)
			(stroke
				(width 0.1)
				(type default)
			)
			(layer "F.Fab")
		)
		(fp_line
			(start 0.120396 0.2794)
			(end -0.12065 0.2794)
			(stroke
				(width 0.1)
				(type default)
			)
			(layer "F.Fab")
		)
		(fp_line
			(start -0.12065 -0.2794)
			(end 0.12065 -0.2794)
			(stroke
				(width 0.1)
				(type default)
			)
			(layer "F.Fab")
		)
		(fp_line
			(start 0.12065 -0.2794)
			(end 0.12065 -0.3048)
			(stroke
				(width 0.1)
				(type default)
			)
			(layer "F.Fab")
		)
		(fp_line
			(start 0.12065 -0.3048)
			(end 0.67945 -0.3048)
			(stroke
				(width 0.1)
				(type default)
			)
			(layer "F.Fab")
		)
		(fp_line
			(start 0.67945 -0.3048)
			(end 0.67945 0.3048)
			(stroke
				(width 0.1)
				(type default)
			)
			(layer "F.Fab")
		)
		(fp_line
			(start -0.67945 -0.305054)
			(end -0.12065 -0.305054)
			(stroke
				(width 0.1)
				(type default)
			)
			(layer "F.Fab")
		)
		(fp_line
			(start -0.12065 -0.305054)
			(end -0.12065 -0.2794)
			(stroke
				(width 0.1)
				(type default)
			)
			(layer "F.Fab")
		)
		(pad "1" smd circle
			(at -0.40005 0 270)
			(size 0 0)
			(layers "F.Cu" "F.Mask" "F.Paste")
			(net "SW_P12V_AUX_PVDDIO_P1_FLT")
		)
		(pad "2" smd circle
			(at 0.40005 0 270)
			(size 0 0)
			(layers "F.Cu" "F.Mask" "F.Paste")
			(net "GND")
		)
	)
)
